# BASEBOARD_FAB2 (Tioga Pass) — schematic netlist excerpt (pin names and nets, part order shuffled) for the footprints in the layout excerpt that follows; sources: Cadence DE-HDL packaged netlist, KiCad conversion of Wiwynn_Tioga_Pass_MB.brd

C3P1  CAP_A  0.1UF 16V 10% EMPTY  pkg 0402V  page 212 : A = VSENSE_PVCCIO_CPU0_SKT_VSEN ; B = VSENSE_PVCCIO_CPU0_SKT_VRTN
C25W45  CAP_A  0.1UF 16V 10% X7R  pkg 0402V  page 149 : A = VCC_D_3V3 ; B = GND
R1L22  RES  200.0 1% CHIP  pkg 0402  page 175 : A = FM_DEBUG_RST_BTN_N ; B = FP_RST_BTN_R_N

(kicad_pcb
	(version 20260206)
	(generator "pcbnew")
	(generator_version "10.0")
	(general
		(thickness 1.6)
		(legacy_teardrops no)
	)
	(paper "A4")
	(title_block
		(title "Wiwynn_Tioga_Pass_MB.brd")
		(comment 1 "Tioga Pass / footprints 3219-3221 of 4770")
	)
	(layers
		(0 "F.Cu" signal "TOP")
		(4 "In1.Cu" signal "L2GND")
		(6 "In2.Cu" signal "L3")
		(8 "In3.Cu" signal "L4GND")
		(10 "In4.Cu" signal "L5")
		(12 "In5.Cu" signal "L6GND")
		(14 "In6.Cu" signal "L7VCC")
		(16 "In7.Cu" signal "L8VCC")
		(18 "In8.Cu" signal "L9GND")
		(20 "In9.Cu" signal "L10")
		(22 "In10.Cu" signal "L11GND")
		(24 "In11.Cu" signal "L12")
		(26 "In12.Cu" signal "L13GND")
		(2 "B.Cu" signal "BOTTOM")
		(9 "F.Adhes" user "F.Adhesive")
		(11 "B.Adhes" user "B.Adhesive")
		(13 "F.Paste" user "Package Geometry/Pastemask Top")
		(15 "B.Paste" user "Package Geometry/Pastemask Bottom")
		(5 "F.SilkS" user "Ref Des/Silkscreen Top")
		(7 "B.SilkS" user "Ref Des/Silkscreen Bottom")
		(1 "F.Mask" user "Board Geometry/Soldermask Top")
		(3 "B.Mask" user "Board Geometry/Soldermask Bottom")
		(17 "Dwgs.User" user "User.Drawings")
		(19 "Cmts.User" user "User.Comments")
		(21 "Eco1.User" user "User.Eco1")
		(23 "Eco2.User" user "User.Eco2")
		(25 "Edge.Cuts" user "Board Geometry/Outline")
		(27 "Margin" user)
		(31 "F.CrtYd" user "Package Geometry/Place Bound Top")
		(29 "B.CrtYd" user "Package Geometry/Place Bound Bottom")
		(35 "F.Fab" user "Ref Des/Assembly Top")
		(33 "B.Fab" user "Ref Des/Assembly Bottom")
	)
	(footprint ""
		(layer "B.Cu")
		(at 355.349048 -86.312248 -90)
		(property "Reference" "C3P1"
			(at 0 0 90)
			(layer "B.SilkS")
			(hide yes)
			(effects
				(font
					(size 1.27 1.27)
				)
				(justify mirror)
			)
		)
		(property "Value" ""
			(at 0 0 90)
			(layer "B.Fab")
			(effects
				(font
					(size 1.27 1.27)
				)
				(justify mirror)
			)
		)
		(duplicate_pad_numbers_are_jumpers no)
		(fp_poly
			(pts
				(xy -0.3048 -0.1016) (xy -0.3048 0.9906) (xy 0.3048 0.9906) (xy 0.3048 -0.1016)
			)
			(stroke
				(width 0)
				(type default)
			)
			(fill no)
			(layer "B.CrtYd")
		)
		(fp_line
			(start -0.3048 0.9906)
			(end -0.3048 -0.1016)
			(stroke
				(width 0.1)
				(type default)
			)
			(layer "B.Fab")
		)
		(fp_line
			(start 0.3048 0.9906)
			(end -0.3048 0.9906)
			(stroke
				(width 0.1)
				(type default)
			)
			(layer "B.Fab")
		)
		(fp_line
			(start -0.3048 -0.1016)
			(end 0.3048 -0.1016)
			(stroke
				(width 0.1)
				(type default)
			)
			(layer "B.Fab")
		)
		(fp_line
			(start 0.3048 -0.1016)
			(end 0.3048 0.9906)
			(stroke
				(width 0.1)
				(type default)
			)
			(layer "B.Fab")
		)
		(pad "1" smd rect
			(at 0 0 90)
			(size 0.508 0.508)
			(layers "B.Cu" "B.Mask" "B.Paste")
			(net "VSENSE_PVCCIO_CPU0_SKT_VSEN")
		)
		(pad "2" smd rect
			(at 0 0.889 90)
			(size 0.508 0.508)
			(layers "B.Cu" "B.Mask" "B.Paste")
			(net "VSENSE_PVCCIO_CPU0_SKT_VRTN")
		)
		(zone
			(layer "B.Cu")
			(hatch none 0.5)
			(connect_pads
				(clearance 0)
			)
			(min_thickness 0.25)
			(keepout
				(tracks not_allowed)
				(vias allowed)
				(pads allowed)
				(copperpour not_allowed)
				(footprints allowed)
			)
			(placement
				(enabled no)
				(sheetname "")
			)
			(fill
				(thermal_gap 0.5)
				(thermal_bridge_width 0.5)
				(island_removal_mode 0)
			)
			(polygon
				(pts
					(xy 354.714048 -86.058248) (xy 354.714048 -86.566248) (xy 355.095048 -86.566248) (xy 355.095048 -86.058248)
				)
			)
		)
		(zone
			(layer "B.Cu")
			(hatch none 0.5)
			(connect_pads
				(clearance 0)
			)
			(min_thickness 0.25)
			(keepout
				(tracks allowed)
				(vias not_allowed)
				(pads allowed)
				(copperpour not_allowed)
				(footprints allowed)
			)
			(placement
				(enabled no)
				(sheetname "")
			)
			(fill
				(thermal_gap 0.5)
				(thermal_bridge_width 0.5)
				(island_removal_mode 0)
			)
			(polygon
				(pts
					(xy 355.095048 -86.058248) (xy 355.095048 -86.566248) (xy 354.714048 -86.566248) (xy 354.714048 -86.058248)
				)
			)
		)
	)
	(footprint ""
		(layer "B.Cu")
		(at 411.5308 -36.5506 90)
		(property "Reference" "C25W45"
			(at 0.8382 -0.67818 90)
			(unlocked yes)
			(layer "B.SilkS")
			(effects
				(font
					(size 0.4064 0.254)
					(thickness 0.1524)
				)
				(justify left mirror)
			)
		)
		(property "Value" ""
			(at 0 0 90)
			(layer "B.Fab")
			(effects
				(font
					(size 1.27 1.27)
				)
				(justify mirror)
			)
		)
		(duplicate_pad_numbers_are_jumpers no)
		(fp_poly
			(pts
				(xy -0.3048 -0.1016) (xy -0.3048 0.9906) (xy 0.3048 0.9906) (xy 0.3048 -0.1016)
			)
			(stroke
				(width 0)
				(type default)
			)
			(fill no)
			(layer "B.CrtYd")
		)
		(fp_line
			(start 0.3048 -0.1016)
			(end 0.3048 0.9906)
			(stroke
				(width 0.1)
				(type default)
			)
			(layer "B.Fab")
		)
		(fp_line
			(start -0.3048 -0.1016)
			(end 0.3048 -0.1016)
			(stroke
				(width 0.1)
				(type default)
			)
			(layer "B.Fab")
		)
		(fp_line
			(start 0.3048 0.9906)
			(end -0.3048 0.9906)
			(stroke
				(width 0.1)
				(type default)
			)
			(layer "B.Fab")
		)
		(fp_line
			(start -0.3048 0.9906)
			(end -0.3048 -0.1016)
			(stroke
				(width 0.1)
				(type default)
			)
			(layer "B.Fab")
		)
		(pad "1" smd rect
			(at 0 0 270)
			(size 0.508 0.508)
			(layers "B.Cu" "B.Mask" "B.Paste")
			(net "VCC_D_3V3")
		)
		(pad "2" smd rect
			(at 0 0.889 270)
			(size 0.508 0.508)
			(layers "B.Cu" "B.Mask" "B.Paste")
			(net "GND")
		)
		(zone
			(layer "B.Cu")
			(hatch none 0.5)
			(connect_pads
				(clearance 0)
			)
			(min_thickness 0.25)
			(keepout
				(tracks allowed)
				(vias not_allowed)
				(pads allowed)
				(copperpour not_allowed)
				(footprints allowed)
			)
			(placement
				(enabled no)
				(sheetname "")
			)
			(fill
				(thermal_gap 0.5)
				(thermal_bridge_width 0.5)
				(island_removal_mode 0)
			)
			(polygon
				(pts
					(xy 411.7848 -36.8046) (xy 411.7848 -36.2966) (xy 412.1658 -36.2966) (xy 412.1658 -36.8046)
				)
			)
		)
		(zone
			(layer "B.Cu")
			(hatch none 0.5)
			(connect_pads
				(clearance 0)
			)
			(min_thickness 0.25)
			(keepout
				(tracks not_allowed)
				(vias allowed)
				(pads allowed)
				(copperpour not_allowed)
				(footprints allowed)
			)
			(placement
				(enabled no)
				(sheetname "")
			)
			(fill
				(thermal_gap 0.5)
				(thermal_bridge_width 0.5)
				(island_removal_mode 0)
			)
			(polygon
				(pts
					(xy 412.1658 -36.8046) (xy 412.1658 -36.2966) (xy 411.7848 -36.2966) (xy 411.7848 -36.8046)
				)
			)
		)
	)
	(footprint ""
		(layer "B.Cu")
		(at 490.15396 -150.18004 -90)
		(property "Reference" "R1L22"
			(at 0 0 90)
			(layer "B.SilkS")
			(hide yes)
			(effects
				(font
					(size 1.27 1.27)
				)
				(justify mirror)
			)
		)
		(property "Value" ""
			(at 0 0 90)
			(layer "B.Fab")
			(effects
				(font
					(size 1.27 1.27)
				)
				(justify mirror)
			)
		)
		(duplicate_pad_numbers_are_jumpers no)
		(fp_poly
			(pts
				(xy 0.2794 -0.1016) (xy -0.2794 -0.1016) (xy -0.2794 0.9906) (xy 0.2794 0.9906)
			)
			(stroke
				(width 0)
				(type default)
			)
			(fill no)
			(layer "B.CrtYd")
		)
		(fp_line
			(start -0.2794 0.9906)
			(end -0.2794 -0.1016)
			(stroke
				(width 0.1)
				(type default)
			)
			(layer "B.Fab")
		)
		(fp_line
			(start 0.2794 0.9906)
			(end -0.2794 0.9906)
			(stroke
				(width 0.1)
				(type default)
			)
			(layer "B.Fab")
		)
		(fp_line
			(start -0.2794 -0.1016)
			(end 0.2794 -0.1016)
			(stroke
				(width 0.1)
				(type default)
			)
			(layer "B.Fab")
		)
		(fp_line
			(start 0.2794 -0.1016)
			(end 0.2794 0.9906)
			(stroke
				(width 0.1)
				(type default)
			)
			(layer "B.Fab")
		)
		(pad "1" smd rect
			(at 0 0 90)
			(size 0.508 0.508)
			(layers "B.Cu" "B.Mask" "B.Paste")
			(net "FM_DEBUG_RST_BTN_N")
		)
		(pad "2" smd rect
			(at 0 0.889 90)
			(size 0.508 0.508)
			(layers "B.Cu" "B.Mask" "B.Paste")
			(net "FP_RST_BTN_R_N")
		)
		(zone
			(layer "B.Cu")
			(hatch none 0.5)
			(connect_pads
				(clearance 0)
			)
			(min_thickness 0.25)
			(keepout
				(tracks not_allowed)
				(vias allowed)
				(pads allowed)
				(copperpour not_allowed)
				(footprints allowed)
			)
			(placement
				(enabled no)
				(sheetname "")
			)
			(fill
				(thermal_gap 0.5)
				(thermal_bridge_width 0.5)
				(island_removal_mode 0)
			)
			(polygon
				(pts
					(xy 489.51896 -149.92604) (xy 489.51896 -150.43404) (xy 489.89996 -150.43404) (xy 489.89996 -149.92604)
				)
			)
		)
		(zone
			(layer "B.Cu")
			(hatch none 0.5)
			(connect_pads
				(clearance 0)
			)
			(min_thickness 0.25)
			(keepout
				(tracks allowed)
				(vias not_allowed)
				(pads allowed)
				(copperpour not_allowed)
				(footprints allowed)
			)
			(placement
				(enabled no)
				(sheetname "")
			)
			(fill
				(thermal_gap 0.5)
				(thermal_bridge_width 0.5)
				(island_removal_mode 0)
			)
			(polygon
				(pts
					(xy 489.89996 -149.92604) (xy 489.89996 -150.43404) (xy 489.51896 -150.43404) (xy 489.51896 -149.92604)
				)
			)
		)
	)
)
